(kicad_pcb
	(version 20260206)
	(generator "pcbnew")
	(generator_version "10.0")
	(general
		(thickness 1.6)
		(legacy_teardrops no)
	)
	(paper "A4")
	(title_block
		(title "01162023_DA0F0TEBIF0_F0T_Expander_BD_F_brd_V02_OCP.brd")
		(comment 1 "Grand Teton / footprints 6938-6940 of 9728")
	)
	(layers
		(0 "F.Cu" signal "TOP")
		(4 "In1.Cu" signal "GND")
		(6 "In2.Cu" signal "VCC")
		(8 "In3.Cu" signal "VCC1")
		(10 "In4.Cu" signal "GND1")
		(12 "In5.Cu" signal "IN1")
		(14 "In6.Cu" signal "GND2")
		(16 "In7.Cu" signal "IN2")
		(18 "In8.Cu" signal "GND3")
		(20 "In9.Cu" signal "IN3")
		(22 "In10.Cu" signal "GND4")
		(24 "In11.Cu" signal "IN4")
		(26 "In12.Cu" signal "GND5")
		(28 "In13.Cu" signal "IN5")
		(30 "In14.Cu" signal "GND6")
		(32 "In15.Cu" signal "IN6")
		(34 "In16.Cu" signal "GND7")
		(2 "B.Cu" signal "BOTTOM")
		(9 "F.Adhes" user "F.Adhesive")
		(11 "B.Adhes" user "B.Adhesive")
		(13 "F.Paste" user "Package Geometry/Pastemask Top")
		(15 "B.Paste" user "Package Geometry/Pastemask Bottom")
		(5 "F.SilkS" user "Ref Des/Silkscreen Top")
		(7 "B.SilkS" user "Ref Des/Silkscreen Bottom")
		(1 "F.Mask" user "Board Geometry/Soldermask Top")
		(3 "B.Mask" user "Board Geometry/Soldermask Bottom")
		(17 "Dwgs.User" user "User.Drawings")
		(19 "Cmts.User" user "User.Comments")
		(21 "Eco1.User" user "User.Eco1")
		(23 "Eco2.User" user "User.Eco2")
		(25 "Edge.Cuts" user "Board Geometry/Outline")
		(27 "Margin" user)
		(31 "F.CrtYd" user "Package Geometry/Place Bound Top")
		(29 "B.CrtYd" user "Package Geometry/Place Bound Bottom")
		(35 "F.Fab" user "Ref Des/Assembly Top")
		(33 "B.Fab" user "Ref Des/Assembly Bottom")
	)
	(footprint ""
		(layer "F.Cu")
		(at 128.201166 -118.343426 -90)
		(property "Reference" "R5962"
			(at 0 0 270)
			(layer "F.SilkS")
			(hide yes)
			(effects
				(font
					(size 1.27 1.27)
				)
			)
		)
		(property "Value" ""
			(at 0 0 270)
			(layer "F.Fab")
			(effects
				(font
					(size 1.27 1.27)
				)
			)
		)
		(duplicate_pad_numbers_are_jumpers no)
		(fp_line
			(start -0.7874 0.4064)
			(end -0.7874 -0.4064)
			(stroke
				(width 0.1524)
				(type default)
			)
			(layer "F.SilkS")
		)
		(fp_line
			(start 0.7874 0.4064)
			(end -0.7874 0.4064)
			(stroke
				(width 0.1524)
				(type default)
			)
			(layer "F.SilkS")
		)
		(fp_line
			(start -0.7874 -0.4064)
			(end 0.7874 -0.4064)
			(stroke
				(width 0.1524)
				(type default)
			)
			(layer "F.SilkS")
		)
		(fp_line
			(start 0.7874 -0.4064)
			(end 0.7874 0.4064)
			(stroke
				(width 0.1524)
				(type default)
			)
			(layer "F.SilkS")
		)
		(fp_line
			(start -0.67945 0.3048)
			(end -0.67945 -0.305054)
			(stroke
				(width 0.1)
				(type default)
			)
			(layer "F.Fab")
		)
		(fp_line
			(start -0.12065 0.3048)
			(end -0.67945 0.3048)
			(stroke
				(width 0.1)
				(type default)
			)
			(layer "F.Fab")
		)
		(fp_line
			(start 0.120396 0.3048)
			(end 0.120396 0.2794)
			(stroke
				(width 0.1)
				(type default)
			)
			(layer "F.Fab")
		)
		(fp_line
			(start 0.67945 0.3048)
			(end 0.120396 0.3048)
			(stroke
				(width 0.1)
				(type default)
			)
			(layer "F.Fab")
		)
		(fp_line
			(start -0.12065 0.2794)
			(end -0.12065 0.3048)
			(stroke
				(width 0.1)
				(type default)
			)
			(layer "F.Fab")
		)
		(fp_line
			(start 0.120396 0.2794)
			(end -0.12065 0.2794)
			(stroke
				(width 0.1)
				(type default)
			)
			(layer "F.Fab")
		)
		(fp_line
			(start -0.12065 -0.2794)
			(end 0.12065 -0.2794)
			(stroke
				(width 0.1)
				(type default)
			)
			(layer "F.Fab")
		)
		(fp_line
			(start 0.12065 -0.2794)
			(end 0.12065 -0.3048)
			(stroke
				(width 0.1)
				(type default)
			)
			(layer "F.Fab")
		)
		(fp_line
			(start 0.12065 -0.3048)
			(end 0.67945 -0.3048)
			(stroke
				(width 0.1)
				(type default)
			)
			(layer "F.Fab")
		)
		(fp_line
			(start 0.67945 -0.3048)
			(end 0.67945 0.3048)
			(stroke
				(width 0.1)
				(type default)
			)
			(layer "F.Fab")
		)
		(fp_line
			(start -0.67945 -0.305054)
			(end -0.12065 -0.305054)
			(stroke
				(width 0.1)
				(type default)
			)
			(layer "F.Fab")
		)
		(fp_line
			(start -0.12065 -0.305054)
			(end -0.12065 -0.2794)
			(stroke
				(width 0.1)
				(type default)
			)
			(layer "F.Fab")
		)
		(pad "1" smd circle
			(at -0.40005 0 270)
			(size 0 0)
			(layers "F.Cu" "F.Mask" "F.Paste")
			(net "P3V3_NIC2")
		)
		(pad "2" smd circle
			(at 0.40005 0 270)
			(size 0 0)
			(layers "F.Cu" "F.Mask" "F.Paste")
			(net "P3V3_NIC2_PG_G1")
		)
	)
	(footprint ""
		(layer "F.Cu")
		(at 115.720114 -260.290564)
		(property "Reference" "PR80"
			(at 0 0 0)
			(layer "F.SilkS")
			(hide yes)
			(effects
				(font
					(size 1.27 1.27)
				)
			)
		)
		(property "Value" ""
			(at 0 0 0)
			(layer "F.Fab")
			(effects
				(font
					(size 1.27 1.27)
				)
			)
		)
		(duplicate_pad_numbers_are_jumpers no)
		(fp_line
			(start -0.7874 -0.4064)
			(end 0.7874 -0.4064)
			(stroke
				(width 0.1524)
				(type default)
			)
			(layer "F.SilkS")
		)
		(fp_line
			(start -0.7874 0.4064)
			(end -0.7874 -0.4064)
			(stroke
				(width 0.1524)
				(type default)
			)
			(layer "F.SilkS")
		)
		(fp_line
			(start 0.7874 -0.4064)
			(end 0.7874 0.4064)
			(stroke
				(width 0.1524)
				(type default)
			)
			(layer "F.SilkS")
		)
		(fp_line
			(start 0.7874 0.4064)
			(end -0.7874 0.4064)
			(stroke
				(width 0.1524)
				(type default)
			)
			(layer "F.SilkS")
		)
		(fp_line
			(start -0.67945 -0.305054)
			(end -0.12065 -0.305054)
			(stroke
				(width 0.1)
				(type default)
			)
			(layer "F.Fab")
		)
		(fp_line
			(start -0.67945 0.3048)
			(end -0.67945 -0.305054)
			(stroke
				(width 0.1)
				(type default)
			)
			(layer "F.Fab")
		)
		(fp_line
			(start -0.12065 -0.305054)
			(end -0.12065 -0.2794)
			(stroke
				(width 0.1)
				(type default)
			)
			(layer "F.Fab")
		)
		(fp_line
			(start -0.12065 -0.2794)
			(end 0.12065 -0.2794)
			(stroke
				(width 0.1)
				(type default)
			)
			(layer "F.Fab")
		)
		(fp_line
			(start -0.12065 0.2794)
			(end -0.12065 0.3048)
			(stroke
				(width 0.1)
				(type default)
			)
			(layer "F.Fab")
		)
		(fp_line
			(start -0.12065 0.3048)
			(end -0.67945 0.3048)
			(stroke
				(width 0.1)
				(type default)
			)
			(layer "F.Fab")
		)
		(fp_line
			(start 0.120396 0.2794)
			(end -0.12065 0.2794)
			(stroke
				(width 0.1)
				(type default)
			)
			(layer "F.Fab")
		)
		(fp_line
			(start 0.120396 0.3048)
			(end 0.120396 0.2794)
			(stroke
				(width 0.1)
				(type default)
			)
			(layer "F.Fab")
		)
		(fp_line
			(start 0.12065 -0.3048)
			(end 0.67945 -0.3048)
			(stroke
				(width 0.1)
				(type default)
			)
			(layer "F.Fab")
		)
		(fp_line
			(start 0.12065 -0.2794)
			(end 0.12065 -0.3048)
			(stroke
				(width 0.1)
				(type default)
			)
			(layer "F.Fab")
		)
		(fp_line
			(start 0.67945 -0.3048)
			(end 0.67945 0.3048)
			(stroke
				(width 0.1)
				(type default)
			)
			(layer "F.Fab")
		)
		(fp_line
			(start 0.67945 0.3048)
			(end 0.120396 0.3048)
			(stroke
				(width 0.1)
				(type default)
			)
			(layer "F.Fab")
		)
		(pad "1" smd circle
			(at -0.40005 0)
			(size 0 0)
			(layers "F.Cu" "F.Mask" "F.Paste")
			(net "SH_P0V8_PEX1_VSEN1_R")
		)
		(pad "2" smd circle
			(at 0.40005 0)
			(size 0 0)
			(layers "F.Cu" "F.Mask" "F.Paste")
			(net "P0V8_PEX1_VSEN1")
		)
	)
	(footprint ""
		(layer "F.Cu")
		(at 210.439 -197.231 180)
		(property "Reference" "R1526"
			(at 0 0 180)
			(layer "F.SilkS")
			(hide yes)
			(effects
				(font
					(size 1.27 1.27)
				)
			)
		)
		(property "Value" ""
			(at 0 0 180)
			(layer "F.Fab")
			(effects
				(font
					(size 1.27 1.27)
				)
			)
		)
		(duplicate_pad_numbers_are_jumpers no)
		(fp_line
			(start 0.7874 0.4064)
			(end -0.7874 0.4064)
			(stroke
				(width 0.1524)
				(type default)
			)
			(layer "F.SilkS")
		)
		(fp_line
			(start 0.7874 -0.4064)
			(end 0.7874 0.4064)
			(stroke
				(width 0.1524)
				(type default)
			)
			(layer "F.SilkS")
		)
		(fp_line
			(start -0.7874 0.4064)
			(end -0.7874 -0.4064)
			(stroke
				(width 0.1524)
				(type default)
			)
			(layer "F.SilkS")
		)
		(fp_line
			(start -0.7874 -0.4064)
			(end 0.7874 -0.4064)
			(stroke
				(width 0.1524)
				(type default)
			)
			(layer "F.SilkS")
		)
		(fp_line
			(start 0.67945 0.3048)
			(end 0.120396 0.3048)
			(stroke
				(width 0.1)
				(type default)
			)
			(layer "F.Fab")
		)
		(fp_line
			(start 0.67945 -0.3048)
			(end 0.67945 0.3048)
			(stroke
				(width 0.1)
				(type default)
			)
			(layer "F.Fab")
		)
		(fp_line
			(start 0.12065 -0.2794)
			(end 0.12065 -0.3048)
			(stroke
				(width 0.1)
				(type default)
			)
			(layer "F.Fab")
		)
		(fp_line
			(start 0.12065 -0.3048)
			(end 0.67945 -0.3048)
			(stroke
				(width 0.1)
				(type default)
			)
			(layer "F.Fab")
		)
		(fp_line
			(start 0.120396 0.3048)
			(end 0.120396 0.2794)
			(stroke
				(width 0.1)
				(type default)
			)
			(layer "F.Fab")
		)
		(fp_line
			(start 0.120396 0.2794)
			(end -0.12065 0.2794)
			(stroke
				(width 0.1)
				(type default)
			)
			(layer "F.Fab")
		)
		(fp_line
			(start -0.12065 0.3048)
			(end -0.67945 0.3048)
			(stroke
				(width 0.1)
				(type default)
			)
			(layer "F.Fab")
		)
		(fp_line
			(start -0.12065 0.2794)
			(end -0.12065 0.3048)
			(stroke
				(width 0.1)
				(type default)
			)
			(layer "F.Fab")
		)
		(fp_line
			(start -0.12065 -0.2794)
			(end 0.12065 -0.2794)
			(stroke
				(width 0.1)
				(type default)
			)
			(layer "F.Fab")
		)
		(fp_line
			(start -0.12065 -0.305054)
			(end -0.12065 -0.2794)
			(stroke
				(width 0.1)
				(type default)
			)
			(layer "F.Fab")
		)
		(fp_line
			(start -0.67945 0.3048)
			(end -0.67945 -0.305054)
			(stroke
				(width 0.1)
				(type default)
			)
			(layer "F.Fab")
		)
		(fp_line
			(start -0.67945 -0.305054)
			(end -0.12065 -0.305054)
			(stroke
				(width 0.1)
				(type default)
			)
			(layer "F.Fab")
		)
		(pad "1" smd circle
			(at -0.40005 0 180)
			(size 0 0)
			(layers "F.Cu" "F.Mask" "F.Paste")
			(net "SMB_NIC6_R_SCL")
		)
		(pad "2" smd circle
			(at 0.40005 0 180)
			(size 0 0)
			(layers "F.Cu" "F.Mask" "F.Paste")
			(net "P1V2_AUX")
		)
	)
)
